(kicad_pcb
	(version 20260206)
	(generator "pcbnew")
	(generator_version "10.0")
	(general
		(thickness 1.6)
		(legacy_teardrops no)
	)
	(paper "A4")
	(title_block
		(title "03242023_DA0F0TMBIJ0_F0T_Motherboard_J_brd_V01_OCP.brd")
		(comment 1 "Grand Teton / footprints 4690-4696 of 6105")
	)
	(layers
		(0 "F.Cu" signal "TOP")
		(4 "In1.Cu" signal "GND")
		(6 "In2.Cu" signal "IN1")
		(8 "In3.Cu" signal "GND1")
		(10 "In4.Cu" signal "IN2")
		(12 "In5.Cu" signal "GND2")
		(14 "In6.Cu" signal "IN3")
		(16 "In7.Cu" signal "GND3")
		(18 "In8.Cu" signal "VCC")
		(20 "In9.Cu" signal "VCC1")
		(22 "In10.Cu" signal "GND4")
		(24 "In11.Cu" signal "IN4")
		(26 "In12.Cu" signal "GND5")
		(28 "In13.Cu" signal "IN5")
		(30 "In14.Cu" signal "GND6")
		(32 "In15.Cu" signal "IN6")
		(34 "In16.Cu" signal "GND7")
		(2 "B.Cu" signal "BOTTOM")
		(9 "F.Adhes" user "F.Adhesive")
		(11 "B.Adhes" user "B.Adhesive")
		(13 "F.Paste" user "Package Geometry/Pastemask Top")
		(15 "B.Paste" user "Package Geometry/Pastemask Bottom")
		(5 "F.SilkS" user "Ref Des/Silkscreen Top")
		(7 "B.SilkS" user "Ref Des/Silkscreen Bottom")
		(1 "F.Mask" user "Board Geometry/Soldermask Top")
		(3 "B.Mask" user "Board Geometry/Soldermask Bottom")
		(17 "Dwgs.User" user "User.Drawings")
		(19 "Cmts.User" user "User.Comments")
		(21 "Eco1.User" user "User.Eco1")
		(23 "Eco2.User" user "User.Eco2")
		(25 "Edge.Cuts" user "Board Geometry/Outline")
		(27 "Margin" user)
		(31 "F.CrtYd" user "Package Geometry/Place Bound Top")
		(29 "B.CrtYd" user "Package Geometry/Place Bound Bottom")
		(35 "F.Fab" user "Ref Des/Assembly Top")
		(33 "B.Fab" user "Ref Des/Assembly Bottom")
	)
	(footprint ""
		(layer "B.Cu")
		(at 342.536526 -334.752442 -90)
		(property "Reference" "PR153"
			(at 0 0 90)
			(layer "B.SilkS")
			(hide yes)
			(effects
				(font
					(size 1.27 1.27)
				)
				(justify mirror)
			)
		)
		(property "Value" ""
			(at 0 0 90)
			(layer "B.Fab")
			(effects
				(font
					(size 1.27 1.27)
				)
				(justify mirror)
			)
		)
		(duplicate_pad_numbers_are_jumpers no)
		(fp_line
			(start -0.7874 0.4064)
			(end 0.7874 0.4064)
			(stroke
				(width 0.1524)
				(type default)
			)
			(layer "B.SilkS")
		)
		(fp_line
			(start 0.7874 0.4064)
			(end 0.7874 -0.4064)
			(stroke
				(width 0.1524)
				(type default)
			)
			(layer "B.SilkS")
		)
		(fp_line
			(start -0.7874 -0.4064)
			(end -0.7874 0.4064)
			(stroke
				(width 0.1524)
				(type default)
			)
			(layer "B.SilkS")
		)
		(fp_line
			(start 0.7874 -0.4064)
			(end -0.7874 -0.4064)
			(stroke
				(width 0.1524)
				(type default)
			)
			(layer "B.SilkS")
		)
		(fp_line
			(start -0.67945 0.3048)
			(end -0.120396 0.3048)
			(stroke
				(width 0.1)
				(type default)
			)
			(layer "B.Fab")
		)
		(fp_line
			(start -0.120396 0.3048)
			(end -0.120396 0.2794)
			(stroke
				(width 0.1)
				(type default)
			)
			(layer "B.Fab")
		)
		(fp_line
			(start 0.12065 0.3048)
			(end 0.67945 0.3048)
			(stroke
				(width 0.1)
				(type default)
			)
			(layer "B.Fab")
		)
		(fp_line
			(start 0.67945 0.3048)
			(end 0.67945 -0.305054)
			(stroke
				(width 0.1)
				(type default)
			)
			(layer "B.Fab")
		)
		(fp_line
			(start -0.120396 0.2794)
			(end 0.12065 0.2794)
			(stroke
				(width 0.1)
				(type default)
			)
			(layer "B.Fab")
		)
		(fp_line
			(start 0.12065 0.2794)
			(end 0.12065 0.3048)
			(stroke
				(width 0.1)
				(type default)
			)
			(layer "B.Fab")
		)
		(fp_line
			(start -0.12065 -0.2794)
			(end -0.12065 -0.3048)
			(stroke
				(width 0.1)
				(type default)
			)
			(layer "B.Fab")
		)
		(fp_line
			(start 0.12065 -0.2794)
			(end -0.12065 -0.2794)
			(stroke
				(width 0.1)
				(type default)
			)
			(layer "B.Fab")
		)
		(fp_line
			(start -0.67945 -0.3048)
			(end -0.67945 0.3048)
			(stroke
				(width 0.1)
				(type default)
			)
			(layer "B.Fab")
		)
		(fp_line
			(start -0.12065 -0.3048)
			(end -0.67945 -0.3048)
			(stroke
				(width 0.1)
				(type default)
			)
			(layer "B.Fab")
		)
		(fp_line
			(start 0.12065 -0.305054)
			(end 0.12065 -0.2794)
			(stroke
				(width 0.1)
				(type default)
			)
			(layer "B.Fab")
		)
		(fp_line
			(start 0.67945 -0.305054)
			(end 0.12065 -0.305054)
			(stroke
				(width 0.1)
				(type default)
			)
			(layer "B.Fab")
		)
		(pad "1" smd circle
			(at 0.40005 0 90)
			(size 0 0)
			(layers "B.Cu" "B.Mask" "B.Paste")
			(net "PVCCIN_CPU0_PVCC")
		)
		(pad "2" smd circle
			(at -0.40005 0 90)
			(size 0 0)
			(layers "B.Cu" "B.Mask" "B.Paste")
			(net "PVCCIN_CPU0_VDD1")
		)
	)
	(footprint ""
		(layer "B.Cu")
		(at 353.619308 -255.853946 -90)
		(property "Reference" "C359"
			(at 0 0 90)
			(layer "B.SilkS")
			(hide yes)
			(effects
				(font
					(size 1.27 1.27)
				)
				(justify mirror)
			)
		)
		(property "Value" ""
			(at 0 0 90)
			(layer "B.Fab")
			(effects
				(font
					(size 1.27 1.27)
				)
				(justify mirror)
			)
		)
		(duplicate_pad_numbers_are_jumpers no)
		(fp_line
			(start -1.524 0.762)
			(end 1.524 0.762)
			(stroke
				(width 0.1524)
				(type default)
			)
			(layer "B.SilkS")
		)
		(fp_line
			(start 1.524 0.762)
			(end 1.524 -0.762)
			(stroke
				(width 0.1524)
				(type default)
			)
			(layer "B.SilkS")
		)
		(fp_line
			(start -1.524 -0.762)
			(end -1.524 0.762)
			(stroke
				(width 0.1524)
				(type default)
			)
			(layer "B.SilkS")
		)
		(fp_line
			(start 1.524 -0.762)
			(end -1.524 -0.762)
			(stroke
				(width 0.1524)
				(type default)
			)
			(layer "B.SilkS")
		)
		(fp_line
			(start -1.1049 0.724916)
			(end -1.1049 -0.724916)
			(stroke
				(width 0.1)
				(type default)
			)
			(layer "B.Fab")
		)
		(fp_line
			(start 1.1049 0.724916)
			(end -1.1049 0.724916)
			(stroke
				(width 0.1)
				(type default)
			)
			(layer "B.Fab")
		)
		(fp_line
			(start -1.1049 -0.724916)
			(end 1.1049 -0.724916)
			(stroke
				(width 0.1)
				(type default)
			)
			(layer "B.Fab")
		)
		(fp_line
			(start 1.1049 -0.724916)
			(end 1.1049 0.724916)
			(stroke
				(width 0.1)
				(type default)
			)
			(layer "B.Fab")
		)
		(pad "1" smd rect
			(at 0.889 0 270)
			(size 1.016 1.27)
			(layers "B.Cu" "B.Mask" "B.Paste")
			(net "PVCCIN_CPU0")
		)
		(pad "2" smd rect
			(at -0.889 0 270)
			(size 1.016 1.27)
			(layers "B.Cu" "B.Mask" "B.Paste")
			(net "GND")
		)
	)
	(footprint ""
		(layer "B.Cu")
		(at 233.971846 -132.475224 -90)
		(property "Reference" "R110"
			(at 0 0 90)
			(layer "B.SilkS")
			(hide yes)
			(effects
				(font
					(size 1.27 1.27)
				)
				(justify mirror)
			)
		)
		(property "Value" ""
			(at 0 0 90)
			(layer "B.Fab")
			(effects
				(font
					(size 1.27 1.27)
				)
				(justify mirror)
			)
		)
		(duplicate_pad_numbers_are_jumpers no)
		(fp_line
			(start -0.7874 0.4064)
			(end 0.7874 0.4064)
			(stroke
				(width 0.1524)
				(type default)
			)
			(layer "B.SilkS")
		)
		(fp_line
			(start 0.7874 0.4064)
			(end 0.7874 -0.4064)
			(stroke
				(width 0.1524)
				(type default)
			)
			(layer "B.SilkS")
		)
		(fp_line
			(start -0.7874 -0.4064)
			(end -0.7874 0.4064)
			(stroke
				(width 0.1524)
				(type default)
			)
			(layer "B.SilkS")
		)
		(fp_line
			(start 0.7874 -0.4064)
			(end -0.7874 -0.4064)
			(stroke
				(width 0.1524)
				(type default)
			)
			(layer "B.SilkS")
		)
		(fp_line
			(start -0.67945 0.3048)
			(end -0.120396 0.3048)
			(stroke
				(width 0.1)
				(type default)
			)
			(layer "B.Fab")
		)
		(fp_line
			(start -0.120396 0.3048)
			(end -0.120396 0.2794)
			(stroke
				(width 0.1)
				(type default)
			)
			(layer "B.Fab")
		)
		(fp_line
			(start 0.12065 0.3048)
			(end 0.67945 0.3048)
			(stroke
				(width 0.1)
				(type default)
			)
			(layer "B.Fab")
		)
		(fp_line
			(start 0.67945 0.3048)
			(end 0.67945 -0.305054)
			(stroke
				(width 0.1)
				(type default)
			)
			(layer "B.Fab")
		)
		(fp_line
			(start -0.120396 0.2794)
			(end 0.12065 0.2794)
			(stroke
				(width 0.1)
				(type default)
			)
			(layer "B.Fab")
		)
		(fp_line
			(start 0.12065 0.2794)
			(end 0.12065 0.3048)
			(stroke
				(width 0.1)
				(type default)
			)
			(layer "B.Fab")
		)
		(fp_line
			(start -0.12065 -0.2794)
			(end -0.12065 -0.3048)
			(stroke
				(width 0.1)
				(type default)
			)
			(layer "B.Fab")
		)
		(fp_line
			(start 0.12065 -0.2794)
			(end -0.12065 -0.2794)
			(stroke
				(width 0.1)
				(type default)
			)
			(layer "B.Fab")
		)
		(fp_line
			(start -0.67945 -0.3048)
			(end -0.67945 0.3048)
			(stroke
				(width 0.1)
				(type default)
			)
			(layer "B.Fab")
		)
		(fp_line
			(start -0.12065 -0.3048)
			(end -0.67945 -0.3048)
			(stroke
				(width 0.1)
				(type default)
			)
			(layer "B.Fab")
		)
		(fp_line
			(start 0.12065 -0.305054)
			(end 0.12065 -0.2794)
			(stroke
				(width 0.1)
				(type default)
			)
			(layer "B.Fab")
		)
		(fp_line
			(start 0.67945 -0.305054)
			(end 0.12065 -0.305054)
			(stroke
				(width 0.1)
				(type default)
			)
			(layer "B.Fab")
		)
		(pad "1" smd circle
			(at 0.40005 0 90)
			(size 0 0)
			(layers "B.Cu" "B.Mask" "B.Paste")
			(net "FM_PLD_CLKS_DEV_R_EN")
		)
		(pad "2" smd circle
			(at -0.40005 0 90)
			(size 0 0)
			(layers "B.Cu" "B.Mask" "B.Paste")
			(net "FM_PLD_CLKS_DEV_EN")
		)
	)
	(footprint ""
		(layer "B.Cu")
		(at 173.91507 -317.48984 90)
		(property "Reference" "R3902"
			(at 0 0 90)
			(layer "B.SilkS")
			(hide yes)
			(effects
				(font
					(size 1.27 1.27)
				)
				(justify mirror)
			)
		)
		(property "Value" ""
			(at 0 0 90)
			(layer "B.Fab")
			(effects
				(font
					(size 1.27 1.27)
				)
				(justify mirror)
			)
		)
		(duplicate_pad_numbers_are_jumpers no)
		(fp_line
			(start 0.7874 -0.4064)
			(end -0.7874 -0.4064)
			(stroke
				(width 0.1524)
				(type default)
			)
			(layer "B.SilkS")
		)
		(fp_line
			(start -0.7874 -0.4064)
			(end -0.7874 0.4064)
			(stroke
				(width 0.1524)
				(type default)
			)
			(layer "B.SilkS")
		)
		(fp_line
			(start 0.7874 0.4064)
			(end 0.7874 -0.4064)
			(stroke
				(width 0.1524)
				(type default)
			)
			(layer "B.SilkS")
		)
		(fp_line
			(start -0.7874 0.4064)
			(end 0.7874 0.4064)
			(stroke
				(width 0.1524)
				(type default)
			)
			(layer "B.SilkS")
		)
		(fp_line
			(start 0.67945 -0.305054)
			(end 0.12065 -0.305054)
			(stroke
				(width 0.1)
				(type default)
			)
			(layer "B.Fab")
		)
		(fp_line
			(start 0.12065 -0.305054)
			(end 0.12065 -0.2794)
			(stroke
				(width 0.1)
				(type default)
			)
			(layer "B.Fab")
		)
		(fp_line
			(start -0.12065 -0.3048)
			(end -0.67945 -0.3048)
			(stroke
				(width 0.1)
				(type default)
			)
			(layer "B.Fab")
		)
		(fp_line
			(start -0.67945 -0.3048)
			(end -0.67945 0.3048)
			(stroke
				(width 0.1)
				(type default)
			)
			(layer "B.Fab")
		)
		(fp_line
			(start 0.12065 -0.2794)
			(end -0.12065 -0.2794)
			(stroke
				(width 0.1)
				(type default)
			)
			(layer "B.Fab")
		)
		(fp_line
			(start -0.12065 -0.2794)
			(end -0.12065 -0.3048)
			(stroke
				(width 0.1)
				(type default)
			)
			(layer "B.Fab")
		)
		(fp_line
			(start 0.12065 0.2794)
			(end 0.12065 0.3048)
			(stroke
				(width 0.1)
				(type default)
			)
			(layer "B.Fab")
		)
		(fp_line
			(start -0.120396 0.2794)
			(end 0.12065 0.2794)
			(stroke
				(width 0.1)
				(type default)
			)
			(layer "B.Fab")
		)
		(fp_line
			(start 0.67945 0.3048)
			(end 0.67945 -0.305054)
			(stroke
				(width 0.1)
				(type default)
			)
			(layer "B.Fab")
		)
		(fp_line
			(start 0.12065 0.3048)
			(end 0.67945 0.3048)
			(stroke
				(width 0.1)
				(type default)
			)
			(layer "B.Fab")
		)
		(fp_line
			(start -0.120396 0.3048)
			(end -0.120396 0.2794)
			(stroke
				(width 0.1)
				(type default)
			)
			(layer "B.Fab")
		)
		(fp_line
			(start -0.67945 0.3048)
			(end -0.120396 0.3048)
			(stroke
				(width 0.1)
				(type default)
			)
			(layer "B.Fab")
		)
		(pad "1" smd circle
			(at 0.40005 0 270)
			(size 0 0)
			(layers "B.Cu" "B.Mask" "B.Paste")
			(net "I3C_SPD_DDREFGH_CPU1_LVC1_SCL_3")
		)
		(pad "2" smd circle
			(at -0.40005 0 270)
			(size 0 0)
			(layers "B.Cu" "B.Mask" "B.Paste")
			(net "I3C_SPD_DDREFGH_CPU1_LVC1_SCL")
		)
	)
	(footprint ""
		(layer "B.Cu")
		(at 24.895302 -163.105846 180)
		(property "Reference" "PR4251"
			(at 0 0 0)
			(layer "B.SilkS")
			(hide yes)
			(effects
				(font
					(size 1.27 1.27)
				)
				(justify mirror)
			)
		)
		(property "Value" ""
			(at 0 0 0)
			(layer "B.Fab")
			(effects
				(font
					(size 1.27 1.27)
				)
				(justify mirror)
			)
		)
		(duplicate_pad_numbers_are_jumpers no)
		(fp_line
			(start 0.7874 0.4064)
			(end 0.7874 -0.4064)
			(stroke
				(width 0.1524)
				(type default)
			)
			(layer "B.SilkS")
		)
		(fp_line
			(start 0.7874 -0.4064)
			(end -0.7874 -0.4064)
			(stroke
				(width 0.1524)
				(type default)
			)
			(layer "B.SilkS")
		)
		(fp_line
			(start -0.7874 0.4064)
			(end 0.7874 0.4064)
			(stroke
				(width 0.1524)
				(type default)
			)
			(layer "B.SilkS")
		)
		(fp_line
			(start -0.7874 -0.4064)
			(end -0.7874 0.4064)
			(stroke
				(width 0.1524)
				(type default)
			)
			(layer "B.SilkS")
		)
		(fp_line
			(start 0.67945 0.3048)
			(end 0.67945 -0.305054)
			(stroke
				(width 0.1)
				(type default)
			)
			(layer "B.Fab")
		)
		(fp_line
			(start 0.67945 -0.305054)
			(end 0.12065 -0.305054)
			(stroke
				(width 0.1)
				(type default)
			)
			(layer "B.Fab")
		)
		(fp_line
			(start 0.12065 0.3048)
			(end 0.67945 0.3048)
			(stroke
				(width 0.1)
				(type default)
			)
			(layer "B.Fab")
		)
		(fp_line
			(start 0.12065 0.2794)
			(end 0.12065 0.3048)
			(stroke
				(width 0.1)
				(type default)
			)
			(layer "B.Fab")
		)
		(fp_line
			(start 0.12065 -0.2794)
			(end -0.12065 -0.2794)
			(stroke
				(width 0.1)
				(type default)
			)
			(layer "B.Fab")
		)
		(fp_line
			(start 0.12065 -0.305054)
			(end 0.12065 -0.2794)
			(stroke
				(width 0.1)
				(type default)
			)
			(layer "B.Fab")
		)
		(fp_line
			(start -0.120396 0.3048)
			(end -0.120396 0.2794)
			(stroke
				(width 0.1)
				(type default)
			)
			(layer "B.Fab")
		)
		(fp_line
			(start -0.120396 0.2794)
			(end 0.12065 0.2794)
			(stroke
				(width 0.1)
				(type default)
			)
			(layer "B.Fab")
		)
		(fp_line
			(start -0.12065 -0.2794)
			(end -0.12065 -0.3048)
			(stroke
				(width 0.1)
				(type default)
			)
			(layer "B.Fab")
		)
		(fp_line
			(start -0.12065 -0.3048)
			(end -0.67945 -0.3048)
			(stroke
				(width 0.1)
				(type default)
			)
			(layer "B.Fab")
		)
		(fp_line
			(start -0.67945 0.3048)
			(end -0.120396 0.3048)
			(stroke
				(width 0.1)
				(type default)
			)
			(layer "B.Fab")
		)
		(fp_line
			(start -0.67945 -0.3048)
			(end -0.67945 0.3048)
			(stroke
				(width 0.1)
				(type default)
			)
			(layer "B.Fab")
		)
		(pad "1" smd circle
			(at 0.40005 0)
			(size 0 0)
			(layers "B.Cu" "B.Mask" "B.Paste")
			(net "NC_PVCCD_HV_CPU1_ACSP2")
		)
		(pad "2" smd circle
			(at -0.40005 0)
			(size 0 0)
			(layers "B.Cu" "B.Mask" "B.Paste")
			(net "GND")
		)
	)
	(footprint ""
		(layer "B.Cu")
		(at 126.65202 -36.761928 90)
		(property "Reference" "R4290"
			(at 0 0 90)
			(layer "B.SilkS")
			(hide yes)
			(effects
				(font
					(size 1.27 1.27)
				)
				(justify mirror)
			)
		)
		(property "Value" ""
			(at 0 0 90)
			(layer "B.Fab")
			(effects
				(font
					(size 1.27 1.27)
				)
				(justify mirror)
			)
		)
		(duplicate_pad_numbers_are_jumpers no)
		(fp_line
			(start 0.7874 -0.4064)
			(end -0.7874 -0.4064)
			(stroke
				(width 0.1524)
				(type default)
			)
			(layer "B.SilkS")
		)
		(fp_line
			(start -0.7874 -0.4064)
			(end -0.7874 0.4064)
			(stroke
				(width 0.1524)
				(type default)
			)
			(layer "B.SilkS")
		)
		(fp_line
			(start 0.7874 0.4064)
			(end 0.7874 -0.4064)
			(stroke
				(width 0.1524)
				(type default)
			)
			(layer "B.SilkS")
		)
		(fp_line
			(start -0.7874 0.4064)
			(end 0.7874 0.4064)
			(stroke
				(width 0.1524)
				(type default)
			)
			(layer "B.SilkS")
		)
		(fp_line
			(start 0.67945 -0.305054)
			(end 0.12065 -0.305054)
			(stroke
				(width 0.1)
				(type default)
			)
			(layer "B.Fab")
		)
		(fp_line
			(start 0.12065 -0.305054)
			(end 0.12065 -0.2794)
			(stroke
				(width 0.1)
				(type default)
			)
			(layer "B.Fab")
		)
		(fp_line
			(start -0.12065 -0.3048)
			(end -0.67945 -0.3048)
			(stroke
				(width 0.1)
				(type default)
			)
			(layer "B.Fab")
		)
		(fp_line
			(start -0.67945 -0.3048)
			(end -0.67945 0.3048)
			(stroke
				(width 0.1)
				(type default)
			)
			(layer "B.Fab")
		)
		(fp_line
			(start 0.12065 -0.2794)
			(end -0.12065 -0.2794)
			(stroke
				(width 0.1)
				(type default)
			)
			(layer "B.Fab")
		)
		(fp_line
			(start -0.12065 -0.2794)
			(end -0.12065 -0.3048)
			(stroke
				(width 0.1)
				(type default)
			)
			(layer "B.Fab")
		)
		(fp_line
			(start 0.12065 0.2794)
			(end 0.12065 0.3048)
			(stroke
				(width 0.1)
				(type default)
			)
			(layer "B.Fab")
		)
		(fp_line
			(start -0.120396 0.2794)
			(end 0.12065 0.2794)
			(stroke
				(width 0.1)
				(type default)
			)
			(layer "B.Fab")
		)
		(fp_line
			(start 0.67945 0.3048)
			(end 0.67945 -0.305054)
			(stroke
				(width 0.1)
				(type default)
			)
			(layer "B.Fab")
		)
		(fp_line
			(start 0.12065 0.3048)
			(end 0.67945 0.3048)
			(stroke
				(width 0.1)
				(type default)
			)
			(layer "B.Fab")
		)
		(fp_line
			(start -0.120396 0.3048)
			(end -0.120396 0.2794)
			(stroke
				(width 0.1)
				(type default)
			)
			(layer "B.Fab")
		)
		(fp_line
			(start -0.67945 0.3048)
			(end -0.120396 0.3048)
			(stroke
				(width 0.1)
				(type default)
			)
			(layer "B.Fab")
		)
		(pad "1" smd circle
			(at 0.40005 0 270)
			(size 0 0)
			(layers "B.Cu" "B.Mask" "B.Paste")
			(net "FM_USB3_1_RXDET_EN")
		)
		(pad "2" smd circle
			(at -0.40005 0 270)
			(size 0 0)
			(layers "B.Cu" "B.Mask" "B.Paste")
			(net "GND")
		)
	)
	(footprint ""
		(layer "B.Cu")
		(at 121.545604 -294.01008 180)
		(property "Reference" "C347"
			(at 0 0 0)
			(layer "B.SilkS")
			(hide yes)
			(effects
				(font
					(size 1.27 1.27)
				)
				(justify mirror)
			)
		)
		(property "Value" ""
			(at 0 0 0)
			(layer "B.Fab")
			(effects
				(font
					(size 1.27 1.27)
				)
				(justify mirror)
			)
		)
		(duplicate_pad_numbers_are_jumpers no)
		(fp_line
			(start 1.524 0.762)
			(end 1.524 -0.762)
			(stroke
				(width 0.1524)
				(type default)
			)
			(layer "B.SilkS")
		)
		(fp_line
			(start 1.524 -0.762)
			(end -1.524 -0.762)
			(stroke
				(width 0.1524)
				(type default)
			)
			(layer "B.SilkS")
		)
		(fp_line
			(start -1.524 0.762)
			(end 1.524 0.762)
			(stroke
				(width 0.1524)
				(type default)
			)
			(layer "B.SilkS")
		)
		(fp_line
			(start -1.524 -0.762)
			(end -1.524 0.762)
			(stroke
				(width 0.1524)
				(type default)
			)
			(layer "B.SilkS")
		)
		(fp_line
			(start 1.1049 0.724916)
			(end -1.1049 0.724916)
			(stroke
				(width 0.1)
				(type default)
			)
			(layer "B.Fab")
		)
		(fp_line
			(start 1.1049 -0.724916)
			(end 1.1049 0.724916)
			(stroke
				(width 0.1)
				(type default)
			)
			(layer "B.Fab")
		)
		(fp_line
			(start -1.1049 0.724916)
			(end -1.1049 -0.724916)
			(stroke
				(width 0.1)
				(type default)
			)
			(layer "B.Fab")
		)
		(fp_line
			(start -1.1049 -0.724916)
			(end 1.1049 -0.724916)
			(stroke
				(width 0.1)
				(type default)
			)
			(layer "B.Fab")
		)
		(pad "1" smd rect
			(at 0.889 0 180)
			(size 1.016 1.27)
			(layers "B.Cu" "B.Mask" "B.Paste")
			(net "PVCCIN_CPU1")
		)
		(pad "2" smd rect
			(at -0.889 0 180)
			(size 1.016 1.27)
			(layers "B.Cu" "B.Mask" "B.Paste")
			(net "GND")
		)
	)
)
